#ISCELL
  mstr_misc dns *
  *
#ISCELL
  mstr_symbols intel_corp_bpage *
  *
#CELL
  mstr_discrete res *
  page89_i1
#ISCELL
  mstr_standard offpage *
  page89_i10
#ISCELL
  mstr_standard offpage *
  page89_i11
#ISCELL
  mstr_standard offpage *
  page89_i12
#ISCELL
  mstr_standard offpage *
  page89_i13
#ISCELL
  mstr_standard offpage *
  page89_i14
#ISCELL
  mstr_symbols gnd *
  page89_i16
#ISCELL
  mstr_symbols pvpp_abc *
  page89_i17
#CELL
  mstr_discrete fet_n *
  page89_i18
#CELL
  mstr_discrete res *
  page89_i2
#ISCELL
  mstr_standard offpage *
  page89_i22
#CELL
  mstr_discrete res *
  page89_i23
#CELL
  mstr_discrete res *
  page89_i26
#CELL
  mstr_discrete res *
  page89_i27
#ISCELL
  mstr_symbols p3v3_stby *
  page89_i28
#ISCELL
  mstr_symbols p3v3_stby *
  page89_i29
#CELL
  mstr_discrete res *
  page89_i3
#ISCELL
  mstr_symbols gnd *
  page89_i30
#ISCELL
  mstr_symbols gnd *
  page89_i31
#ISCELL
  mstr_standard offpage *
  page89_i33
#CELL
  mstr_discrete res *
  page89_i34
#CELL
  mstr_discrete npn_dual *
  page89_i35
#CELL
  mstr_discrete npn_dual *
  page89_i36
#CELL
  mstr_discrete res *
  page89_i4
#CELL
  mstr_discrete res *
  page89_i5
#CELL
  mstr_discrete res *
  page89_i6
#CELL
  mstr_discrete res *
  page89_i7
#ISCELL
  mstr_standard offpage *
  page89_i9
